(kicad_pcb
	(version 20260206)
	(generator "pcbnew")
	(generator_version "10.0")
	(general
		(thickness 1.6)
		(legacy_teardrops no)
	)
	(paper "A4")
	(title_block
		(title "peb — Lightning_PEB_BRD.brd")
		(comment 1 "Lightning (Wiwynn / Facebook NVMe JBOF) / footprints 716-723 of 2563")
	)
	(layers
		(0 "F.Cu" signal "TOP")
		(4 "In1.Cu" signal "L2GND")
		(6 "In2.Cu" signal "L3")
		(8 "In3.Cu" signal "L4VCC")
		(10 "In4.Cu" signal "L5VCC")
		(12 "In5.Cu" signal "L6")
		(14 "In6.Cu" signal "L7GND")
		(2 "B.Cu" signal "BOTTOM")
		(9 "F.Adhes" user "F.Adhesive")
		(11 "B.Adhes" user "B.Adhesive")
		(13 "F.Paste" user "Package Geometry/Pastemask Top")
		(15 "B.Paste" user "Package Geometry/Pastemask Bottom")
		(5 "F.SilkS" user "Ref Des/Silkscreen Top")
		(7 "B.SilkS" user "Ref Des/Silkscreen Bottom")
		(1 "F.Mask" user "Board Geometry/Soldermask Top")
		(3 "B.Mask" user "Board Geometry/Soldermask Bottom")
		(17 "Dwgs.User" user "User.Drawings")
		(19 "Cmts.User" user "User.Comments")
		(21 "Eco1.User" user "User.Eco1")
		(23 "Eco2.User" user "User.Eco2")
		(25 "Edge.Cuts" user "Board Geometry/Outline")
		(27 "Margin" user)
		(31 "F.CrtYd" user "Package Geometry/Place Bound Top")
		(29 "B.CrtYd" user "Package Geometry/Place Bound Bottom")
		(35 "F.Fab" user "Ref Des/Assembly Top")
		(33 "B.Fab" user "Ref Des/Assembly Bottom")
	)
	(footprint ""
		(layer "F.Cu")
		(at 127.060452 -33.5915)
		(property "Reference" "R2934"
			(at 0 0 0)
			(layer "F.SilkS")
			(hide yes)
			(effects
				(font
					(size 1.27 1.27)
				)
			)
		)
		(property "Value" "0R2J-2-GP"
			(at 0.064008 -3.993896 0)
			(unlocked yes)
			(layer "F.Fab")
			(hide yes)
			(effects
				(font
					(size 1.016 1.016)
					(thickness 0.1524)
				)
			)
		)
		(property "Device Type" "R402H16"
			(at 0.064008 -5.517896 0)
			(unlocked yes)
			(layer "F.Fab")
			(hide yes)
			(effects
				(font
					(size 1.016 1.016)
					(thickness 0.1524)
				)
			)
		)
		(duplicate_pad_numbers_are_jumpers no)
		(fp_line
			(start -0.508 -0.9398)
			(end -0.508 0.9398)
			(stroke
				(width 0.1524)
				(type default)
			)
			(layer "F.SilkS")
		)
		(fp_line
			(start 0.508 -0.9398)
			(end -0.508 -0.9398)
			(stroke
				(width 0.1524)
				(type default)
			)
			(layer "F.SilkS")
		)
		(fp_rect
			(start -0.508 0.9398)
			(end 0.508 -0.9398)
			(stroke
				(width 0)
				(type default)
			)
			(fill no)
			(layer "F.CrtYd")
		)
		(fp_rect
			(start -0.508 0.9398)
			(end 0.508 -0.9398)
			(stroke
				(width 0)
				(type default)
			)
			(fill no)
			(layer "F.Fab")
		)
		(pad "1" smd custom
			(at 0 -0.4445)
			(size 0.1397 0.1397)
			(layers "F.Cu" "F.Mask" "F.Paste")
			(net "USB2_BMC_DN")
			(options
				(clearance outline)
				(anchor circle)
			)
			(primitives
				(gr_poly
					(pts
						(arc
							(start -0.1778 -0.2794)
							(mid -0.249642 -0.249642)
							(end -0.2794 -0.1778)
						)
						(arc
							(start -0.2794 0.1778)
							(mid -0.249642 0.249642)
							(end -0.1778 0.2794)
						)
						(arc
							(start 0.1778 0.2794)
							(mid 0.249642 0.249642)
							(end 0.2794 0.1778)
						)
						(arc
							(start 0.2794 -0.1778)
							(mid 0.249642 -0.249642)
							(end 0.1778 -0.2794)
						)
					)
					(width 0)
					(fill yes)
				)
			)
		)
		(pad "2" smd custom
			(at 0 0.4445)
			(size 0.1397 0.1397)
			(layers "F.Cu" "F.Mask" "F.Paste")
			(net "8644_USB_DN1")
			(options
				(clearance outline)
				(anchor circle)
			)
			(primitives
				(gr_poly
					(pts
						(arc
							(start -0.1778 -0.2794)
							(mid -0.249642 -0.249642)
							(end -0.2794 -0.1778)
						)
						(arc
							(start -0.2794 0.1778)
							(mid -0.249642 0.249642)
							(end -0.1778 0.2794)
						)
						(arc
							(start 0.1778 0.2794)
							(mid 0.249642 0.249642)
							(end 0.2794 0.1778)
						)
						(arc
							(start 0.2794 -0.1778)
							(mid 0.249642 -0.249642)
							(end 0.1778 -0.2794)
						)
					)
					(width 0)
					(fill yes)
				)
			)
		)
	)
	(footprint ""
		(layer "F.Cu")
		(at 298.063666 -33.495234 180)
		(property "Reference" "R720"
			(at 0 0 180)
			(layer "F.SilkS")
			(hide yes)
			(effects
				(font
					(size 1.27 1.27)
				)
			)
		)
		(property "Value" "0R2J-2-GP"
			(at 0.064008 -3.993896 180)
			(unlocked yes)
			(layer "F.Fab")
			(hide yes)
			(effects
				(font
					(size 1.016 1.016)
					(thickness 0.1524)
				)
			)
		)
		(property "Device Type" "R402H16"
			(at 0.064008 -5.517896 180)
			(unlocked yes)
			(layer "F.Fab")
			(hide yes)
			(effects
				(font
					(size 1.016 1.016)
					(thickness 0.1524)
				)
			)
		)
		(duplicate_pad_numbers_are_jumpers no)
		(fp_line
			(start 0.508 -0.9398)
			(end -0.508 -0.9398)
			(stroke
				(width 0.1524)
				(type default)
			)
			(layer "F.SilkS")
		)
		(fp_line
			(start -0.508 -0.9398)
			(end -0.508 0.9398)
			(stroke
				(width 0.1524)
				(type default)
			)
			(layer "F.SilkS")
		)
		(fp_rect
			(start -0.508 0.9398)
			(end 0.508 -0.9398)
			(stroke
				(width 0)
				(type default)
			)
			(fill no)
			(layer "F.CrtYd")
		)
		(fp_rect
			(start -0.508 0.9398)
			(end 0.508 -0.9398)
			(stroke
				(width 0)
				(type default)
			)
			(fill no)
			(layer "F.Fab")
		)
		(pad "1" smd custom
			(at 0 -0.4445 180)
			(size 0.1397 0.1397)
			(layers "F.Cu" "F.Mask" "F.Paste")
			(net "8644_USB_DP6")
			(options
				(clearance outline)
				(anchor circle)
			)
			(primitives
				(gr_poly
					(pts
						(arc
							(start -0.1778 -0.2794)
							(mid -0.249642 -0.249642)
							(end -0.2794 -0.1778)
						)
						(arc
							(start -0.2794 0.1778)
							(mid -0.249642 0.249642)
							(end -0.1778 0.2794)
						)
						(arc
							(start 0.1778 0.2794)
							(mid 0.249642 0.249642)
							(end 0.2794 0.1778)
						)
						(arc
							(start 0.2794 -0.1778)
							(mid 0.249642 -0.249642)
							(end 0.1778 -0.2794)
						)
					)
					(width 0)
					(fill yes)
				)
			)
		)
		(pad "2" smd custom
			(at 0 0.4445 180)
			(size 0.1397 0.1397)
			(layers "F.Cu" "F.Mask" "F.Paste")
			(net "P3V3_STBY")
			(options
				(clearance outline)
				(anchor circle)
			)
			(primitives
				(gr_poly
					(pts
						(arc
							(start -0.1778 -0.2794)
							(mid -0.249642 -0.249642)
							(end -0.2794 -0.1778)
						)
						(arc
							(start -0.2794 0.1778)
							(mid -0.249642 0.249642)
							(end -0.1778 0.2794)
						)
						(arc
							(start 0.1778 0.2794)
							(mid 0.249642 0.249642)
							(end 0.2794 0.1778)
						)
						(arc
							(start 0.2794 -0.1778)
							(mid 0.249642 -0.249642)
							(end 0.1778 -0.2794)
						)
					)
					(width 0)
					(fill yes)
				)
			)
		)
	)
	(footprint ""
		(layer "F.Cu")
		(at 158.461202 -60.479432 90)
		(property "Reference" "PR628"
			(at 0 0 90)
			(layer "F.SilkS")
			(hide yes)
			(effects
				(font
					(size 1.27 1.27)
				)
			)
		)
		(property "Value" "4K7R2F-GP"
			(at 0.064008 -3.993896 90)
			(unlocked yes)
			(layer "F.Fab")
			(hide yes)
			(effects
				(font
					(size 1.016 1.016)
					(thickness 0.1524)
				)
			)
		)
		(property "Device Type" "R402H16"
			(at 0.064008 -5.517896 90)
			(unlocked yes)
			(layer "F.Fab")
			(hide yes)
			(effects
				(font
					(size 1.016 1.016)
					(thickness 0.1524)
				)
			)
		)
		(duplicate_pad_numbers_are_jumpers no)
		(fp_line
			(start 0.508 -0.9398)
			(end -0.508 -0.9398)
			(stroke
				(width 0.1524)
				(type default)
			)
			(layer "F.SilkS")
		)
		(fp_line
			(start -0.508 -0.9398)
			(end -0.508 0.9398)
			(stroke
				(width 0.1524)
				(type default)
			)
			(layer "F.SilkS")
		)
		(fp_rect
			(start -0.508 0.9398)
			(end 0.508 -0.9398)
			(stroke
				(width 0)
				(type default)
			)
			(fill no)
			(layer "F.CrtYd")
		)
		(fp_rect
			(start -0.508 0.9398)
			(end 0.508 -0.9398)
			(stroke
				(width 0)
				(type default)
			)
			(fill no)
			(layer "F.Fab")
		)
		(pad "1" smd custom
			(at 0 -0.4445 90)
			(size 0.1397 0.1397)
			(layers "F.Cu" "F.Mask" "F.Paste")
			(net "P0V9_PG")
			(options
				(clearance outline)
				(anchor circle)
			)
			(primitives
				(gr_poly
					(pts
						(arc
							(start -0.1778 -0.2794)
							(mid -0.249642 -0.249642)
							(end -0.2794 -0.1778)
						)
						(arc
							(start -0.2794 0.1778)
							(mid -0.249642 0.249642)
							(end -0.1778 0.2794)
						)
						(arc
							(start 0.1778 0.2794)
							(mid 0.249642 0.249642)
							(end 0.2794 0.1778)
						)
						(arc
							(start 0.2794 -0.1778)
							(mid 0.249642 -0.249642)
							(end 0.1778 -0.2794)
						)
					)
					(width 0)
					(fill yes)
				)
			)
		)
		(pad "2" smd custom
			(at 0 0.4445 90)
			(size 0.1397 0.1397)
			(layers "F.Cu" "F.Mask" "F.Paste")
			(net "P3V3_STBY")
			(options
				(clearance outline)
				(anchor circle)
			)
			(primitives
				(gr_poly
					(pts
						(arc
							(start -0.1778 -0.2794)
							(mid -0.249642 -0.249642)
							(end -0.2794 -0.1778)
						)
						(arc
							(start -0.2794 0.1778)
							(mid -0.249642 0.249642)
							(end -0.1778 0.2794)
						)
						(arc
							(start 0.1778 0.2794)
							(mid 0.249642 0.249642)
							(end 0.2794 0.1778)
						)
						(arc
							(start 0.2794 -0.1778)
							(mid 0.249642 -0.249642)
							(end 0.1778 -0.2794)
						)
					)
					(width 0)
					(fill yes)
				)
			)
		)
	)
	(footprint ""
		(layer "F.Cu")
		(at 339.598 -71.501 180)
		(property "Reference" "PSP2"
			(at 0 0 180)
			(layer "F.SilkS")
			(hide yes)
			(effects
				(font
					(size 1.27 1.27)
				)
			)
		)
		(property "Value" "COPPER-CLOSE-GP-U"
			(at 0.0762 -2.8702 180)
			(unlocked yes)
			(layer "F.Fab")
			(hide yes)
			(effects
				(font
					(size 1.016 1.016)
					(thickness 0.1524)
				)
			)
		)
		(property "Device Type" "CON2C-U"
			(at 0.0762 -4.3942 180)
			(unlocked yes)
			(layer "F.Fab")
			(hide yes)
			(effects
				(font
					(size 1.016 1.016)
					(thickness 0.1524)
				)
			)
		)
		(duplicate_pad_numbers_are_jumpers no)
		(fp_rect
			(start -0.9398 0.9652)
			(end 0.9398 -0.9652)
			(stroke
				(width 0)
				(type default)
			)
			(fill no)
			(layer "F.CrtYd")
		)
		(fp_rect
			(start -0.9398 0.9652)
			(end 0.9398 -0.9652)
			(stroke
				(width 0)
				(type default)
			)
			(fill no)
			(layer "F.Fab")
		)
		(pad "1" smd custom
			(at 0 -0.5334 180)
			(size 0.17145 0.17145)
			(layers "F.Cu" "F.Mask" "F.Paste")
			(net "GND")
			(options
				(clearance outline)
				(anchor circle)
			)
			(primitives
				(gr_poly
					(pts
						(xy -0.127 0.3429) (xy -0.127 0.1651) (xy -0.635 -0.3429) (xy 0.635 -0.3429) (xy 0.127 0.1651)
						(xy 0.127 0.3429)
					)
					(width 0)
					(fill yes)
				)
			)
		)
		(pad "2" smd custom
			(at 0 0.5334 180)
			(size 0.17145 0.17145)
			(layers "F.Cu" "F.Mask" "F.Paste")
			(net "AGND_P0V9_E")
			(options
				(clearance outline)
				(anchor circle)
			)
			(primitives
				(gr_poly
					(pts
						(xy -0.635 0.3429) (xy -0.127 -0.1651) (xy -0.127 -0.3429) (xy 0.127 -0.3429) (xy 0.127 -0.1651)
						(xy 0.635 0.3429)
					)
					(width 0)
					(fill yes)
				)
			)
		)
	)
	(footprint ""
		(layer "F.Cu")
		(at 310.007 -62.4586)
		(property "Reference" "PG44"
			(at 0 0 0)
			(layer "F.SilkS")
			(hide yes)
			(effects
				(font
					(size 1.27 1.27)
				)
			)
		)
		(property "Value" "GAP-CLOSE-PWR-3-GP"
			(at 0.0254 -6.5786 0)
			(unlocked yes)
			(layer "F.Fab")
			(hide yes)
			(effects
				(font
					(size 1.016 1.016)
					(thickness 0.1524)
				)
			)
		)
		(property "Device Type" "GAP-CLOSE-PWR-3"
			(at 0.0254 -8.255 0)
			(unlocked yes)
			(layer "F.Fab")
			(hide yes)
			(effects
				(font
					(size 1.016 1.016)
					(thickness 0.1524)
				)
			)
		)
		(duplicate_pad_numbers_are_jumpers no)
		(fp_rect
			(start -0.7112 0.4572)
			(end 0.7112 -0.4572)
			(stroke
				(width 0)
				(type default)
			)
			(fill no)
			(layer "F.CrtYd")
		)
		(fp_poly
			(pts
				(xy -0.7112 -0.4572) (xy 0.7112 -0.4572) (xy 0.7112 0.4572) (xy -0.7112 0.4572)
			)
			(stroke
				(width 0)
				(type default)
			)
			(fill no)
			(layer "F.Fab")
		)
		(pad "1" smd rect
			(at -0.3048 0)
			(size 0.6604 0.762)
			(layers "F.Cu" "F.Mask" "F.Paste")
			(net "DUT_VDD")
		)
		(pad "2" smd rect
			(at 0.3048 0)
			(size 0.6604 0.762)
			(layers "F.Cu" "F.Mask" "F.Paste")
			(net "P0V9_E")
		)
	)
	(footprint ""
		(layer "F.Cu")
		(at 340.233 -52.07 -90)
		(property "Reference" "PC216"
			(at 0 0 270)
			(layer "F.SilkS")
			(hide yes)
			(effects
				(font
					(size 1.27 1.27)
				)
			)
		)
		(property "Value" "SC22U25V6KX-GP-U"
			(at -2.860802 -5.279644 270)
			(unlocked yes)
			(layer "F.Fab")
			(hide yes)
			(effects
				(font
					(size 1.016 1.016)
					(thickness 0.1524)
				)
			)
		)
		(property "Device Type" "C1206-TO0D3H75"
			(at -2.860802 -6.803644 270)
			(unlocked yes)
			(layer "F.Fab")
			(hide yes)
			(effects
				(font
					(size 1.016 1.016)
					(thickness 0.1524)
				)
			)
		)
		(duplicate_pad_numbers_are_jumpers no)
		(fp_line
			(start -1.3081 2.3749)
			(end -1.3081 -2.3749)
			(stroke
				(width 0.1524)
				(type default)
			)
			(layer "F.SilkS")
		)
		(fp_line
			(start 1.3081 2.3749)
			(end -1.3081 2.3749)
			(stroke
				(width 0.1524)
				(type default)
			)
			(layer "F.SilkS")
		)
		(fp_line
			(start -1.3081 -2.3749)
			(end 1.3081 -2.3749)
			(stroke
				(width 0.1524)
				(type default)
			)
			(layer "F.SilkS")
		)
		(fp_line
			(start 1.3081 -2.3749)
			(end 1.3081 2.3749)
			(stroke
				(width 0.1524)
				(type default)
			)
			(layer "F.SilkS")
		)
		(fp_rect
			(start -0.8001 1.6002)
			(end 0.8001 -1.6002)
			(stroke
				(width 0)
				(type default)
			)
			(fill no)
			(layer "F.CrtYd")
		)
		(fp_poly
			(pts
				(xy -1.5621 2.4511) (xy -1.5621 1.6002) (xy 0.8001 1.6002) (xy 0.8001 -1.6002) (xy -0.8001 -1.6002)
				(xy -0.8001 1.5875) (xy -1.5621 1.5875) (xy -1.5621 -2.4511) (xy 1.5621 -2.4511) (xy 1.5621 2.4511)
			)
			(stroke
				(width 0)
				(type default)
			)
			(fill no)
			(layer "F.CrtYd")
		)
		(fp_rect
			(start -1.5621 2.4511)
			(end 1.5621 -2.4511)
			(stroke
				(width 0)
				(type default)
			)
			(fill no)
			(layer "F.Fab")
		)
		(pad "1" smd rect
			(at 0 -1.392936 270)
			(size 2.1082 1.4478)
			(layers "F.Cu" "F.Mask" "F.Paste")
			(net "P0V9_E_VIN")
		)
		(pad "2" smd rect
			(at 0 1.392936 270)
			(size 2.1082 1.4478)
			(layers "F.Cu" "F.Mask" "F.Paste")
			(net "GND")
		)
	)
	(footprint ""
		(layer "F.Cu")
		(at 205.359 -21.971 -90)
		(property "Reference" "R69"
			(at 0 0 270)
			(layer "F.SilkS")
			(hide yes)
			(effects
				(font
					(size 1.27 1.27)
				)
			)
		)
		(property "Value" "0R2J-2-GP"
			(at 0.064008 -3.993896 270)
			(unlocked yes)
			(layer "F.Fab")
			(hide yes)
			(effects
				(font
					(size 1.016 1.016)
					(thickness 0.1524)
				)
			)
		)
		(property "Device Type" "R402H16"
			(at 0.064008 -5.517896 270)
			(unlocked yes)
			(layer "F.Fab")
			(hide yes)
			(effects
				(font
					(size 1.016 1.016)
					(thickness 0.1524)
				)
			)
		)
		(duplicate_pad_numbers_are_jumpers no)
		(fp_line
			(start -0.508 -0.9398)
			(end -0.508 0.9398)
			(stroke
				(width 0.1524)
				(type default)
			)
			(layer "F.SilkS")
		)
		(fp_line
			(start 0.508 -0.9398)
			(end -0.508 -0.9398)
			(stroke
				(width 0.1524)
				(type default)
			)
			(layer "F.SilkS")
		)
		(fp_rect
			(start -0.508 0.9398)
			(end 0.508 -0.9398)
			(stroke
				(width 0)
				(type default)
			)
			(fill no)
			(layer "F.CrtYd")
		)
		(fp_rect
			(start -0.508 0.9398)
			(end 0.508 -0.9398)
			(stroke
				(width 0)
				(type default)
			)
			(fill no)
			(layer "F.Fab")
		)
		(pad "1" smd custom
			(at 0 -0.4445 270)
			(size 0.1397 0.1397)
			(layers "F.Cu" "F.Mask" "F.Paste")
			(net "TCA9554_INT_N")
			(options
				(clearance outline)
				(anchor circle)
			)
			(primitives
				(gr_poly
					(pts
						(arc
							(start -0.1778 -0.2794)
							(mid -0.249642 -0.249642)
							(end -0.2794 -0.1778)
						)
						(arc
							(start -0.2794 0.1778)
							(mid -0.249642 0.249642)
							(end -0.1778 0.2794)
						)
						(arc
							(start 0.1778 0.2794)
							(mid 0.249642 0.249642)
							(end 0.2794 0.1778)
						)
						(arc
							(start 0.2794 -0.1778)
							(mid 0.249642 -0.249642)
							(end 0.1778 -0.2794)
						)
					)
					(width 0)
					(fill yes)
				)
			)
		)
		(pad "2" smd custom
			(at 0 0.4445 270)
			(size 0.1397 0.1397)
			(layers "F.Cu" "F.Mask" "F.Paste")
			(net "U56_INT_N")
			(options
				(clearance outline)
				(anchor circle)
			)
			(primitives
				(gr_poly
					(pts
						(arc
							(start -0.1778 -0.2794)
							(mid -0.249642 -0.249642)
							(end -0.2794 -0.1778)
						)
						(arc
							(start -0.2794 0.1778)
							(mid -0.249642 0.249642)
							(end -0.1778 0.2794)
						)
						(arc
							(start 0.1778 0.2794)
							(mid 0.249642 0.249642)
							(end 0.2794 0.1778)
						)
						(arc
							(start 0.2794 -0.1778)
							(mid 0.249642 -0.249642)
							(end 0.1778 -0.2794)
						)
					)
					(width 0)
					(fill yes)
				)
			)
		)
	)
	(footprint ""
		(layer "F.Cu")
		(at 51.562 -135.763)
		(property "Reference" "TP160"
			(at 0 0 0)
			(layer "F.SilkS")
			(hide yes)
			(effects
				(font
					(size 1.27 1.27)
				)
			)
		)
		(property "Value" "TPAD28-2-GP"
			(at -0.0127 -1.6637 0)
			(unlocked yes)
			(layer "F.Fab")
			(hide yes)
			(effects
				(font
					(size 1.016 1.016)
					(thickness 0.1524)
				)
			)
		)
		(property "Device Type" "TPAD28"
			(at -0.0127 -3.1877 0)
			(unlocked yes)
			(layer "F.Fab")
			(hide yes)
			(effects
				(font
					(size 1.016 1.016)
					(thickness 0.1524)
				)
			)
		)
		(duplicate_pad_numbers_are_jumpers no)
		(fp_poly
			(pts
				(arc
					(start 0.3556 0)
					(mid -0.3556 0)
					(end 0.3556 0)
				)
			)
			(stroke
				(width 0)
				(type default)
			)
			(fill no)
			(layer "F.CrtYd")
		)
		(fp_poly
			(pts
				(arc
					(start 0.6096 0)
					(mid -0.6096 0)
					(end 0.6096 0)
				)
			)
			(stroke
				(width 0)
				(type default)
			)
			(fill no)
			(layer "F.Fab")
		)
		(pad "1" smd circle
			(at 0 0)
			(size 0.7112 0.7112)
			(layers "F.Cu" "F.Mask" "F.Paste")
			(net "TP_BMC_GPIOJ5")
		)
	)
)
